# BASEBOARD_FAB2 (Tioga Pass) — schematic netlist excerpt (pin names and nets, part order shuffled) for the footprints in the layout excerpt that follows; sources: Cadence DE-HDL packaged netlist, KiCad conversion of Wiwynn_Tioga_Pass_MB.brd

R4G20  RES  2 1.0% CHIP  pkg 0402  page 98 : A = M_C_CPU_VREF ; B = M_C_VREF
C2D10  CAP  10UF 4V 20% X6S  pkg 0603LF  page 76 : A = PVSA_CPU1 ; B = GND
R7B5  RES  1.00K 1% CHIP  pkg 0402  page 218 : A = P3V3_STBY ; B = PWRGD_PVDDQ_DEF_R

(kicad_pcb
	(version 20260206)
	(generator "pcbnew")
	(generator_version "10.0")
	(general
		(thickness 1.6)
		(legacy_teardrops no)
	)
	(paper "A4")
	(title_block
		(title "Wiwynn_Tioga_Pass_MB.brd")
		(comment 1 "Tioga Pass / footprints 1875-1877 of 4770")
	)
	(layers
		(0 "F.Cu" signal "TOP")
		(4 "In1.Cu" signal "L2GND")
		(6 "In2.Cu" signal "L3")
		(8 "In3.Cu" signal "L4GND")
		(10 "In4.Cu" signal "L5")
		(12 "In5.Cu" signal "L6GND")
		(14 "In6.Cu" signal "L7VCC")
		(16 "In7.Cu" signal "L8VCC")
		(18 "In8.Cu" signal "L9GND")
		(20 "In9.Cu" signal "L10")
		(22 "In10.Cu" signal "L11GND")
		(24 "In11.Cu" signal "L12")
		(26 "In12.Cu" signal "L13GND")
		(2 "B.Cu" signal "BOTTOM")
		(9 "F.Adhes" user "F.Adhesive")
		(11 "B.Adhes" user "B.Adhesive")
		(13 "F.Paste" user "Package Geometry/Pastemask Top")
		(15 "B.Paste" user "Package Geometry/Pastemask Bottom")
		(5 "F.SilkS" user "Ref Des/Silkscreen Top")
		(7 "B.SilkS" user "Ref Des/Silkscreen Bottom")
		(1 "F.Mask" user "Board Geometry/Soldermask Top")
		(3 "B.Mask" user "Board Geometry/Soldermask Bottom")
		(17 "Dwgs.User" user "User.Drawings")
		(19 "Cmts.User" user "User.Comments")
		(21 "Eco1.User" user "User.Eco1")
		(23 "Eco2.User" user "User.Eco2")
		(25 "Edge.Cuts" user "Board Geometry/Outline")
		(27 "Margin" user)
		(31 "F.CrtYd" user "Package Geometry/Place Bound Top")
		(29 "B.CrtYd" user "Package Geometry/Place Bound Bottom")
		(35 "F.Fab" user "Ref Des/Assembly Top")
		(33 "B.Fab" user "Ref Des/Assembly Bottom")
	)
	(footprint ""
		(layer "F.Cu")
		(at 94.50324 -81.573116)
		(property "Reference" "C2D10"
			(at 0 0 0)
			(layer "F.SilkS")
			(hide yes)
			(effects
				(font
					(size 1.27 1.27)
				)
			)
		)
		(property "Value" ""
			(at 0 0 0)
			(layer "F.Fab")
			(effects
				(font
					(size 1.27 1.27)
				)
			)
		)
		(duplicate_pad_numbers_are_jumpers no)
		(fp_poly
			(pts
				(xy -0.4953 -0.2032) (xy 0.4953 -0.2032) (xy 0.4953 1.6002) (xy -0.4953 1.6002)
			)
			(stroke
				(width 0)
				(type default)
			)
			(fill no)
			(layer "F.CrtYd")
		)
		(fp_line
			(start -0.4953 -0.2032)
			(end 0.4953 -0.2032)
			(stroke
				(width 0.1)
				(type default)
			)
			(layer "F.Fab")
		)
		(fp_line
			(start -0.4953 1.6002)
			(end -0.4953 -0.2032)
			(stroke
				(width 0.1)
				(type default)
			)
			(layer "F.Fab")
		)
		(fp_line
			(start 0.4953 -0.2032)
			(end 0.4953 1.6002)
			(stroke
				(width 0.1)
				(type default)
			)
			(layer "F.Fab")
		)
		(fp_line
			(start 0.4953 1.6002)
			(end -0.4953 1.6002)
			(stroke
				(width 0.1)
				(type default)
			)
			(layer "F.Fab")
		)
		(pad "1" smd rect
			(at 0 0)
			(size 0.762 0.889)
			(layers "F.Cu" "F.Mask" "F.Paste")
			(net "PVSA_CPU1")
		)
		(pad "2" smd rect
			(at 0 1.397)
			(size 0.762 0.889)
			(layers "F.Cu" "F.Mask" "F.Paste")
			(net "GND")
		)
		(zone
			(layer "F.Cu")
			(hatch none 0.5)
			(connect_pads
				(clearance 0)
			)
			(min_thickness 0.25)
			(keepout
				(tracks not_allowed)
				(vias allowed)
				(pads allowed)
				(copperpour not_allowed)
				(footprints allowed)
			)
			(placement
				(enabled no)
				(sheetname "")
			)
			(fill
				(thermal_gap 0.5)
				(thermal_bridge_width 0.5)
				(island_removal_mode 0)
			)
			(polygon
				(pts
					(xy 94.12224 -81.128616) (xy 94.88424 -81.128616) (xy 94.88424 -80.620616) (xy 94.12224 -80.620616)
				)
			)
		)
	)
	(footprint ""
		(layer "F.Cu")
		(at 192.786 -3.7465)
		(property "Reference" "R4G20"
			(at 0 0 0)
			(layer "F.SilkS")
			(hide yes)
			(effects
				(font
					(size 1.27 1.27)
				)
			)
		)
		(property "Value" ""
			(at 0 0 0)
			(layer "F.Fab")
			(effects
				(font
					(size 1.27 1.27)
				)
			)
		)
		(duplicate_pad_numbers_are_jumpers no)
		(fp_poly
			(pts
				(xy -0.2794 -0.1016) (xy 0.2794 -0.1016) (xy 0.2794 0.9906) (xy -0.2794 0.9906)
			)
			(stroke
				(width 0)
				(type default)
			)
			(fill no)
			(layer "F.CrtYd")
		)
		(fp_line
			(start -0.2794 -0.1016)
			(end -0.2794 0.9906)
			(stroke
				(width 0.1)
				(type default)
			)
			(layer "F.Fab")
		)
		(fp_line
			(start -0.2794 0.9906)
			(end 0.2794 0.9906)
			(stroke
				(width 0.1)
				(type default)
			)
			(layer "F.Fab")
		)
		(fp_line
			(start 0.2794 -0.1016)
			(end -0.2794 -0.1016)
			(stroke
				(width 0.1)
				(type default)
			)
			(layer "F.Fab")
		)
		(fp_line
			(start 0.2794 0.9906)
			(end 0.2794 -0.1016)
			(stroke
				(width 0.1)
				(type default)
			)
			(layer "F.Fab")
		)
		(pad "1" smd rect
			(at 0 0)
			(size 0.508 0.508)
			(layers "F.Cu" "F.Mask" "F.Paste")
			(net "M_C_CPU_VREF")
		)
		(pad "2" smd rect
			(at 0 0.889)
			(size 0.508 0.508)
			(layers "F.Cu" "F.Mask" "F.Paste")
			(net "M_C_VREF")
		)
		(zone
			(layer "F.Cu")
			(hatch none 0.5)
			(connect_pads
				(clearance 0)
			)
			(min_thickness 0.25)
			(keepout
				(tracks allowed)
				(vias not_allowed)
				(pads allowed)
				(copperpour not_allowed)
				(footprints allowed)
			)
			(placement
				(enabled no)
				(sheetname "")
			)
			(fill
				(thermal_gap 0.5)
				(thermal_bridge_width 0.5)
				(island_removal_mode 0)
			)
			(polygon
				(pts
					(xy 192.532 -3.4925) (xy 193.04 -3.4925) (xy 193.04 -3.1115) (xy 192.532 -3.1115)
				)
			)
		)
		(zone
			(layer "F.Cu")
			(hatch none 0.5)
			(connect_pads
				(clearance 0)
			)
			(min_thickness 0.25)
			(keepout
				(tracks not_allowed)
				(vias allowed)
				(pads allowed)
				(copperpour not_allowed)
				(footprints allowed)
			)
			(placement
				(enabled no)
				(sheetname "")
			)
			(fill
				(thermal_gap 0.5)
				(thermal_bridge_width 0.5)
				(island_removal_mode 0)
			)
			(polygon
				(pts
					(xy 192.532 -3.1115) (xy 193.04 -3.1115) (xy 193.04 -3.4925) (xy 192.532 -3.4925)
				)
			)
		)
	)
	(footprint ""
		(layer "F.Cu")
		(at 362.09224 -133.08457 180)
		(property "Reference" "R7B5"
			(at 0 0 180)
			(layer "F.SilkS")
			(hide yes)
			(effects
				(font
					(size 1.27 1.27)
				)
			)
		)
		(property "Value" ""
			(at 0 0 180)
			(layer "F.Fab")
			(effects
				(font
					(size 1.27 1.27)
				)
			)
		)
		(duplicate_pad_numbers_are_jumpers no)
		(fp_rect
			(start 0.2794 -0.1016)
			(end -0.2794 0.9906)
			(stroke
				(width 0)
				(type default)
			)
			(fill no)
			(layer "F.CrtYd")
		)
		(fp_line
			(start 0.2794 0.9906)
			(end 0.2794 -0.1016)
			(stroke
				(width 0.1)
				(type default)
			)
			(layer "F.Fab")
		)
		(fp_line
			(start 0.2794 -0.1016)
			(end -0.2794 -0.1016)
			(stroke
				(width 0.1)
				(type default)
			)
			(layer "F.Fab")
		)
		(fp_line
			(start -0.2794 0.9906)
			(end 0.2794 0.9906)
			(stroke
				(width 0.1)
				(type default)
			)
			(layer "F.Fab")
		)
		(fp_line
			(start -0.2794 -0.1016)
			(end -0.2794 0.9906)
			(stroke
				(width 0.1)
				(type default)
			)
			(layer "F.Fab")
		)
		(pad "1" smd rect
			(at 0 0 180)
			(size 0.508 0.508)
			(layers "F.Cu" "F.Mask" "F.Paste")
			(net "P3V3_STBY")
		)
		(pad "2" smd rect
			(at 0 0.889 180)
			(size 0.508 0.508)
			(layers "F.Cu" "F.Mask" "F.Paste")
			(net "PWRGD_PVDDQ_DEF_R")
		)
		(zone
			(layer "F.Cu")
			(hatch none 0.5)
			(connect_pads
				(clearance 0)
			)
			(min_thickness 0.25)
			(keepout
				(tracks allowed)
				(vias not_allowed)
				(pads allowed)
				(copperpour not_allowed)
				(footprints allowed)
			)
			(placement
				(enabled no)
				(sheetname "")
			)
			(fill
				(thermal_gap 0.5)
				(thermal_bridge_width 0.5)
				(island_removal_mode 0)
			)
			(polygon
				(pts
					(xy 361.83824 -133.33857) (xy 362.34624 -133.33857) (xy 362.34624 -133.71957) (xy 361.83824 -133.71957)
				)
			)
		)
		(zone
			(layer "F.Cu")
			(hatch none 0.5)
			(connect_pads
				(clearance 0)
			)
			(min_thickness 0.25)
			(keepout
				(tracks not_allowed)
				(vias allowed)
				(pads allowed)
				(copperpour not_allowed)
				(footprints allowed)
			)
			(placement
				(enabled no)
				(sheetname "")
			)
			(fill
				(thermal_gap 0.5)
				(thermal_bridge_width 0.5)
				(island_removal_mode 0)
			)
			(polygon
				(pts
					(xy 361.83824 -133.33857) (xy 362.34624 -133.33857) (xy 362.34624 -133.71957) (xy 361.83824 -133.71957)
				)
			)
		)
	)
)
